(kicad_pcb
	(version 20260206)
	(generator "pcbnew")
	(generator_version "10.0")
	(general
		(thickness 1.6)
		(legacy_teardrops no)
	)
	(paper "A4")
	(title_block
		(title "9052_F0T_PDB_Converter_Brick_F_V03_1208_1600_OCP.brd")
		(comment 1 "Grand Teton / footprints 198-204 of 578")
	)
	(layers
		(0 "F.Cu" signal "TOP")
		(4 "In1.Cu" signal "GND")
		(6 "In2.Cu" signal "IN1")
		(8 "In3.Cu" signal "GND1")
		(10 "In4.Cu" signal "VCC")
		(12 "In5.Cu" signal "VCC1")
		(14 "In6.Cu" signal "GND2")
		(16 "In7.Cu" signal "IN2")
		(18 "In8.Cu" signal "GND3")
		(2 "B.Cu" signal "BOTTOM")
		(9 "F.Adhes" user "F.Adhesive")
		(11 "B.Adhes" user "B.Adhesive")
		(13 "F.Paste" user "Package Geometry/Pastemask Top")
		(15 "B.Paste" user "Package Geometry/Pastemask Bottom")
		(5 "F.SilkS" user "Ref Des/Silkscreen Top")
		(7 "B.SilkS" user "Ref Des/Silkscreen Bottom")
		(1 "F.Mask" user "Board Geometry/Soldermask Top")
		(3 "B.Mask" user "Board Geometry/Soldermask Bottom")
		(17 "Dwgs.User" user "User.Drawings")
		(19 "Cmts.User" user "User.Comments")
		(21 "Eco1.User" user "User.Eco1")
		(23 "Eco2.User" user "User.Eco2")
		(25 "Edge.Cuts" user "Board Geometry/Outline")
		(27 "Margin" user)
		(31 "F.CrtYd" user "Package Geometry/Place Bound Top")
		(29 "B.CrtYd" user "Package Geometry/Place Bound Bottom")
		(35 "F.Fab" user "Ref Des/Assembly Top")
		(33 "B.Fab" user "Ref Des/Assembly Bottom")
	)
	(footprint ""
		(layer "F.Cu")
		(at 280.39568 -114.412268)
		(property "Reference" "PQ2"
			(at -7.723886 -5.895848 0)
			(unlocked yes)
			(layer "F.SilkS")
			(effects
				(font
					(size 0.7874 0.5842)
					(thickness 0.1524)
				)
				(justify left)
			)
		)
		(property "Value" ""
			(at 0 0 0)
			(layer "F.Fab")
			(effects
				(font
					(size 1.27 1.27)
				)
			)
		)
		(duplicate_pad_numbers_are_jumpers no)
		(fp_line
			(start -7.649972 -4.99999)
			(end -7.649972 -3.3274)
			(stroke
				(width 0.1524)
				(type default)
			)
			(layer "F.SilkS")
		)
		(fp_line
			(start -7.649972 -1.7526)
			(end -7.649972 1.7526)
			(stroke
				(width 0.1524)
				(type default)
			)
			(layer "F.SilkS")
		)
		(fp_line
			(start -7.649972 3.3274)
			(end -7.649972 4.99999)
			(stroke
				(width 0.1524)
				(type default)
			)
			(layer "F.SilkS")
		)
		(fp_line
			(start -7.649972 4.99999)
			(end 5.115814 4.99999)
			(stroke
				(width 0.1524)
				(type default)
			)
			(layer "F.SilkS")
		)
		(fp_line
			(start 5.115814 -4.99999)
			(end -7.649972 -4.99999)
			(stroke
				(width 0.1524)
				(type default)
			)
			(layer "F.SilkS")
		)
		(fp_line
			(start 7.630414 4.99999)
			(end 7.649972 4.99999)
			(stroke
				(width 0.1524)
				(type default)
			)
			(layer "F.SilkS")
		)
		(fp_line
			(start 7.649972 -4.99999)
			(end 7.630414 -4.99999)
			(stroke
				(width 0.1524)
				(type default)
			)
			(layer "F.SilkS")
		)
		(fp_line
			(start 7.649972 4.99999)
			(end 7.649972 -4.99999)
			(stroke
				(width 0.1524)
				(type default)
			)
			(layer "F.SilkS")
		)
		(fp_line
			(start -7.649972 -4.99999)
			(end -7.649972 4.99999)
			(stroke
				(width 0.1)
				(type default)
			)
			(layer "F.Fab")
		)
		(fp_line
			(start -7.649972 4.99999)
			(end 7.649972 4.99999)
			(stroke
				(width 0.1)
				(type default)
			)
			(layer "F.Fab")
		)
		(fp_line
			(start 7.649972 -4.99999)
			(end -7.649972 -4.99999)
			(stroke
				(width 0.1)
				(type default)
			)
			(layer "F.Fab")
		)
		(fp_line
			(start 7.649972 4.99999)
			(end 7.649972 -4.99999)
			(stroke
				(width 0.1)
				(type default)
			)
			(layer "F.Fab")
		)
		(pad "D" smd circle
			(at 2.15011 0)
			(size 0 0)
			(layers "F.Cu" "F.Mask" "F.Paste")
			(net "P52V_HS1_DRAIN_1")
		)
		(pad "G" smd rect
			(at -7.050024 -2.54 270)
			(size 1.3208 3.0988)
			(layers "F.Cu" "F.Mask" "F.Paste")
			(net "P52V_HS1_GATE2")
		)
		(pad "S" smd rect
			(at -7.050024 2.54 270)
			(size 1.3208 3.0988)
			(layers "F.Cu" "F.Mask" "F.Paste")
			(net "P52V_HS")
		)
		(zone
			(layer "F.Cu")
			(hatch none 0.5)
			(connect_pads
				(clearance 0)
			)
			(min_thickness 0.25)
			(keepout
				(tracks not_allowed)
				(vias allowed)
				(pads allowed)
				(copperpour not_allowed)
				(footprints allowed)
			)
			(placement
				(enabled no)
				(sheetname "")
			)
			(fill
				(thermal_gap 0.5)
				(thermal_bridge_width 0.5)
				(island_removal_mode 0)
			)
			(polygon
				(pts
					(xy 285.57728 -119.390668) (xy 272.75028 -119.390668) (xy 272.75028 -117.663468) (xy 274.96008 -117.663468)
					(xy 274.96008 -116.241068) (xy 272.75028 -116.241068) (xy 272.75028 -112.583468) (xy 274.96008 -112.583468)
					(xy 274.96008 -111.161068) (xy 272.75028 -111.161068) (xy 272.75028 -109.433868) (xy 285.57728 -109.433868)
					(xy 285.57728 -110.602268) (xy 279.37968 -110.602268) (xy 279.37968 -118.222268) (xy 285.57728 -118.222268)
				)
			)
		)
	)
	(footprint ""
		(layer "F.Cu")
		(at 281.960574 -58.862214)
		(property "Reference" "PR6966"
			(at 0 0 0)
			(layer "F.SilkS")
			(hide yes)
			(effects
				(font
					(size 1.27 1.27)
				)
			)
		)
		(property "Value" ""
			(at 0 0 0)
			(layer "F.Fab")
			(effects
				(font
					(size 1.27 1.27)
				)
			)
		)
		(duplicate_pad_numbers_are_jumpers no)
		(fp_line
			(start -0.7874 -0.4064)
			(end 0.7874 -0.4064)
			(stroke
				(width 0.1524)
				(type default)
			)
			(layer "F.SilkS")
		)
		(fp_line
			(start -0.7874 0.4064)
			(end -0.7874 -0.4064)
			(stroke
				(width 0.1524)
				(type default)
			)
			(layer "F.SilkS")
		)
		(fp_line
			(start 0.7874 -0.4064)
			(end 0.7874 0.4064)
			(stroke
				(width 0.1524)
				(type default)
			)
			(layer "F.SilkS")
		)
		(fp_line
			(start 0.7874 0.4064)
			(end -0.7874 0.4064)
			(stroke
				(width 0.1524)
				(type default)
			)
			(layer "F.SilkS")
		)
		(fp_line
			(start -0.67945 -0.305054)
			(end -0.12065 -0.305054)
			(stroke
				(width 0.1)
				(type default)
			)
			(layer "F.Fab")
		)
		(fp_line
			(start -0.67945 0.3048)
			(end -0.67945 -0.305054)
			(stroke
				(width 0.1)
				(type default)
			)
			(layer "F.Fab")
		)
		(fp_line
			(start -0.12065 -0.305054)
			(end -0.12065 -0.2794)
			(stroke
				(width 0.1)
				(type default)
			)
			(layer "F.Fab")
		)
		(fp_line
			(start -0.12065 -0.2794)
			(end 0.12065 -0.2794)
			(stroke
				(width 0.1)
				(type default)
			)
			(layer "F.Fab")
		)
		(fp_line
			(start -0.12065 0.2794)
			(end -0.12065 0.3048)
			(stroke
				(width 0.1)
				(type default)
			)
			(layer "F.Fab")
		)
		(fp_line
			(start -0.12065 0.3048)
			(end -0.67945 0.3048)
			(stroke
				(width 0.1)
				(type default)
			)
			(layer "F.Fab")
		)
		(fp_line
			(start 0.120396 0.2794)
			(end -0.12065 0.2794)
			(stroke
				(width 0.1)
				(type default)
			)
			(layer "F.Fab")
		)
		(fp_line
			(start 0.120396 0.3048)
			(end 0.120396 0.2794)
			(stroke
				(width 0.1)
				(type default)
			)
			(layer "F.Fab")
		)
		(fp_line
			(start 0.12065 -0.3048)
			(end 0.67945 -0.3048)
			(stroke
				(width 0.1)
				(type default)
			)
			(layer "F.Fab")
		)
		(fp_line
			(start 0.12065 -0.2794)
			(end 0.12065 -0.3048)
			(stroke
				(width 0.1)
				(type default)
			)
			(layer "F.Fab")
		)
		(fp_line
			(start 0.67945 -0.3048)
			(end 0.67945 0.3048)
			(stroke
				(width 0.1)
				(type default)
			)
			(layer "F.Fab")
		)
		(fp_line
			(start 0.67945 0.3048)
			(end 0.120396 0.3048)
			(stroke
				(width 0.1)
				(type default)
			)
			(layer "F.Fab")
		)
		(pad "1" smd rect
			(at -0.40005 0 180)
			(size 0.4572 0.508)
			(layers "F.Cu" "F.Mask" "F.Paste")
			(net "P52V_HS1_TEMP")
		)
		(pad "2" smd rect
			(at 0.40005 0 180)
			(size 0.4572 0.508)
			(layers "F.Cu" "F.Mask" "F.Paste")
			(net "P52V_HS1_TEMP_R")
		)
	)
	(footprint ""
		(layer "F.Cu")
		(at 44.713906 -130.175)
		(property "Reference" "PC75"
			(at 0 0 0)
			(layer "F.SilkS")
			(hide yes)
			(effects
				(font
					(size 1.27 1.27)
				)
			)
		)
		(property "Value" ""
			(at 0 0 0)
			(layer "F.Fab")
			(effects
				(font
					(size 1.27 1.27)
				)
			)
		)
		(duplicate_pad_numbers_are_jumpers no)
		(fp_line
			(start -2.2098 -0.9398)
			(end 2.2098 -0.9398)
			(stroke
				(width 0.1524)
				(type default)
			)
			(layer "F.SilkS")
		)
		(fp_line
			(start -2.2098 0.9398)
			(end -2.2098 -0.9398)
			(stroke
				(width 0.1524)
				(type default)
			)
			(layer "F.SilkS")
		)
		(fp_line
			(start 2.2098 -0.9398)
			(end 2.2098 0.9398)
			(stroke
				(width 0.1524)
				(type default)
			)
			(layer "F.SilkS")
		)
		(fp_line
			(start 2.2098 0.9398)
			(end -2.2098 0.9398)
			(stroke
				(width 0.1524)
				(type default)
			)
			(layer "F.SilkS")
		)
		(fp_line
			(start -1.700022 -0.899922)
			(end 1.700022 -0.899922)
			(stroke
				(width 0.1)
				(type default)
			)
			(layer "F.Fab")
		)
		(fp_line
			(start -1.700022 0.899922)
			(end -1.700022 -0.899922)
			(stroke
				(width 0.1)
				(type default)
			)
			(layer "F.Fab")
		)
		(fp_line
			(start 1.700022 -0.899922)
			(end 1.700022 0.899922)
			(stroke
				(width 0.1)
				(type default)
			)
			(layer "F.Fab")
		)
		(fp_line
			(start 1.700022 0.899922)
			(end -1.700022 0.899922)
			(stroke
				(width 0.1)
				(type default)
			)
			(layer "F.Fab")
		)
		(pad "1" smd rect
			(at -1.4732 0 180)
			(size 1.1684 1.5748)
			(layers "F.Cu" "F.Mask" "F.Paste")
			(net "P52V_HS_FILTER")
		)
		(pad "2" smd rect
			(at 1.4732 0 180)
			(size 1.1684 1.5748)
			(layers "F.Cu" "F.Mask" "F.Paste")
			(net "GND")
		)
	)
	(footprint ""
		(layer "F.Cu")
		(at 311.410096 -44.304966)
		(property "Reference" "H25"
			(at -1.9812 -4.079748 0)
			(unlocked yes)
			(layer "B.SilkS")
			(effects
				(font
					(size 0.7874 0.5842)
					(thickness 0.1524)
				)
				(justify left mirror)
			)
		)
		(property "Value" ""
			(at 0 0 0)
			(layer "F.Fab")
			(effects
				(font
					(size 1.27 1.27)
				)
			)
		)
		(duplicate_pad_numbers_are_jumpers no)
		(pad "1" thru_hole circle
			(at 0 0)
			(size 8.001 8.001)
			(drill 4.2418)
			(layers "*.Cu" "*.Mask")
			(remove_unused_layers no)
			(net "H25_TP")
			(clearance -1.6256)
			(padstack
				(mode front_inner_back)
				(layer "Inner"
					(shape circle)
					(size 6.0198 6.0198)
					(clearance -0.635)
				)
				(layer "B.Cu"
					(shape circle)
					(size 8.001 8.001)
					(clearance -1.6256)
				)
			)
		)
		(zone
			(layers "F.Cu" "B.Cu" "In1.Cu" "In2.Cu" "In3.Cu" "In4.Cu" "In5.Cu" "In6.Cu"
				"In7.Cu" "In8.Cu"
			)
			(hatch none 0.5)
			(connect_pads
				(clearance 0)
			)
			(min_thickness 0.25)
			(keepout
				(tracks not_allowed)
				(vias allowed)
				(pads allowed)
				(copperpour not_allowed)
				(footprints allowed)
			)
			(placement
				(enabled no)
				(sheetname "")
			)
			(fill
				(thermal_gap 0.5)
				(thermal_bridge_width 0.5)
				(island_removal_mode 0)
			)
			(polygon
				(pts
					(arc
						(start 314.920122 -44.304966)
						(mid 307.90007 -44.304966)
						(end 314.920122 -44.304966)
					)
				)
			)
		)
	)
	(footprint ""
		(layer "F.Cu")
		(at 280.924 -49.276 90)
		(property "Reference" "PC9"
			(at 0 0 90)
			(layer "F.SilkS")
			(hide yes)
			(effects
				(font
					(size 1.27 1.27)
				)
			)
		)
		(property "Value" ""
			(at 0 0 90)
			(layer "F.Fab")
			(effects
				(font
					(size 1.27 1.27)
				)
			)
		)
		(duplicate_pad_numbers_are_jumpers no)
		(fp_line
			(start 0.7874 -0.4064)
			(end 0.7874 0.4064)
			(stroke
				(width 0.1524)
				(type default)
			)
			(layer "F.SilkS")
		)
		(fp_line
			(start -0.7874 -0.4064)
			(end 0.7874 -0.4064)
			(stroke
				(width 0.1524)
				(type default)
			)
			(layer "F.SilkS")
		)
		(fp_line
			(start 0.7874 0.4064)
			(end -0.7874 0.4064)
			(stroke
				(width 0.1524)
				(type default)
			)
			(layer "F.SilkS")
		)
		(fp_line
			(start -0.7874 0.4064)
			(end -0.7874 -0.4064)
			(stroke
				(width 0.1524)
				(type default)
			)
			(layer "F.SilkS")
		)
		(fp_line
			(start -0.12065 -0.305054)
			(end -0.12065 -0.2794)
			(stroke
				(width 0.1)
				(type default)
			)
			(layer "F.Fab")
		)
		(fp_line
			(start -0.67945 -0.305054)
			(end -0.12065 -0.305054)
			(stroke
				(width 0.1)
				(type default)
			)
			(layer "F.Fab")
		)
		(fp_line
			(start 0.67945 -0.3048)
			(end 0.67945 0.3048)
			(stroke
				(width 0.1)
				(type default)
			)
			(layer "F.Fab")
		)
		(fp_line
			(start 0.12065 -0.3048)
			(end 0.67945 -0.3048)
			(stroke
				(width 0.1)
				(type default)
			)
			(layer "F.Fab")
		)
		(fp_line
			(start 0.12065 -0.2794)
			(end 0.12065 -0.3048)
			(stroke
				(width 0.1)
				(type default)
			)
			(layer "F.Fab")
		)
		(fp_line
			(start -0.12065 -0.2794)
			(end 0.12065 -0.2794)
			(stroke
				(width 0.1)
				(type default)
			)
			(layer "F.Fab")
		)
		(fp_line
			(start 0.120396 0.2794)
			(end -0.12065 0.2794)
			(stroke
				(width 0.1)
				(type default)
			)
			(layer "F.Fab")
		)
		(fp_line
			(start -0.12065 0.2794)
			(end -0.12065 0.3048)
			(stroke
				(width 0.1)
				(type default)
			)
			(layer "F.Fab")
		)
		(fp_line
			(start 0.67945 0.3048)
			(end 0.120396 0.3048)
			(stroke
				(width 0.1)
				(type default)
			)
			(layer "F.Fab")
		)
		(fp_line
			(start 0.120396 0.3048)
			(end 0.120396 0.2794)
			(stroke
				(width 0.1)
				(type default)
			)
			(layer "F.Fab")
		)
		(fp_line
			(start -0.12065 0.3048)
			(end -0.67945 0.3048)
			(stroke
				(width 0.1)
				(type default)
			)
			(layer "F.Fab")
		)
		(fp_line
			(start -0.67945 0.3048)
			(end -0.67945 -0.305054)
			(stroke
				(width 0.1)
				(type default)
			)
			(layer "F.Fab")
		)
		(pad "1" smd circle
			(at -0.40005 0 90)
			(size 0 0)
			(layers "F.Cu" "F.Mask" "F.Paste")
			(net "P52V_HS1_RND")
		)
		(pad "2" smd circle
			(at 0.40005 0 90)
			(size 0 0)
			(layers "F.Cu" "F.Mask" "F.Paste")
			(net "GND_FIELD_SIGNAL")
		)
	)
	(footprint ""
		(layer "F.Cu")
		(at 60.452 -62.865)
		(property "Reference" "PC84"
			(at 0 0 0)
			(layer "F.SilkS")
			(hide yes)
			(effects
				(font
					(size 1.27 1.27)
				)
			)
		)
		(property "Value" ""
			(at 0 0 0)
			(layer "F.Fab")
			(effects
				(font
					(size 1.27 1.27)
				)
			)
		)
		(duplicate_pad_numbers_are_jumpers no)
		(fp_line
			(start -0.7874 -0.4064)
			(end 0.7874 -0.4064)
			(stroke
				(width 0.1524)
				(type default)
			)
			(layer "F.SilkS")
		)
		(fp_line
			(start -0.7874 0.4064)
			(end -0.7874 -0.4064)
			(stroke
				(width 0.1524)
				(type default)
			)
			(layer "F.SilkS")
		)
		(fp_line
			(start 0.7874 -0.4064)
			(end 0.7874 0.4064)
			(stroke
				(width 0.1524)
				(type default)
			)
			(layer "F.SilkS")
		)
		(fp_line
			(start 0.7874 0.4064)
			(end -0.7874 0.4064)
			(stroke
				(width 0.1524)
				(type default)
			)
			(layer "F.SilkS")
		)
		(fp_line
			(start -0.6858 -0.3048)
			(end -0.1016 -0.3048)
			(stroke
				(width 0.1)
				(type default)
			)
			(layer "F.Fab")
		)
		(fp_line
			(start -0.6858 0.3048)
			(end -0.6858 -0.3048)
			(stroke
				(width 0.1)
				(type default)
			)
			(layer "F.Fab")
		)
		(fp_line
			(start -0.1016 -0.3048)
			(end -0.1016 -0.2794)
			(stroke
				(width 0.1)
				(type default)
			)
			(layer "F.Fab")
		)
		(fp_line
			(start -0.1016 -0.2794)
			(end 0.1016 -0.2794)
			(stroke
				(width 0.1)
				(type default)
			)
			(layer "F.Fab")
		)
		(fp_line
			(start -0.1016 0.2794)
			(end -0.1016 0.3048)
			(stroke
				(width 0.1)
				(type default)
			)
			(layer "F.Fab")
		)
		(fp_line
			(start -0.1016 0.3048)
			(end -0.6858 0.3048)
			(stroke
				(width 0.1)
				(type default)
			)
			(layer "F.Fab")
		)
		(fp_line
			(start 0.1016 -0.3048)
			(end 0.6858 -0.3048)
			(stroke
				(width 0.1)
				(type default)
			)
			(layer "F.Fab")
		)
		(fp_line
			(start 0.1016 -0.2794)
			(end 0.1016 -0.3048)
			(stroke
				(width 0.1)
				(type default)
			)
			(layer "F.Fab")
		)
		(fp_line
			(start 0.1016 0.2794)
			(end -0.1016 0.2794)
			(stroke
				(width 0.1)
				(type default)
			)
			(layer "F.Fab")
		)
		(fp_line
			(start 0.1016 0.3048)
			(end 0.1016 0.2794)
			(stroke
				(width 0.1)
				(type default)
			)
			(layer "F.Fab")
		)
		(fp_line
			(start 0.6858 -0.3048)
			(end 0.6858 0.3048)
			(stroke
				(width 0.1)
				(type default)
			)
			(layer "F.Fab")
		)
		(fp_line
			(start 0.6858 0.3048)
			(end 0.1016 0.3048)
			(stroke
				(width 0.1)
				(type default)
			)
			(layer "F.Fab")
		)
		(pad "1" smd rect
			(at -0.40005 0 180)
			(size 0.4572 0.508)
			(layers "F.Cu" "F.Mask" "F.Paste")
			(net "P12V_BRICK")
		)
		(pad "2" smd rect
			(at 0.40005 0 180)
			(size 0.4572 0.508)
			(layers "F.Cu" "F.Mask" "F.Paste")
			(net "GND")
		)
	)
	(footprint ""
		(layer "F.Cu")
		(at 169.291 -60.96)
		(property "Reference" "PC41"
			(at -1.27 -3.52933 0)
			(unlocked yes)
			(layer "F.SilkS")
			(effects
				(font
					(size 0.7874 0.5842)
					(thickness 0.1524)
				)
				(justify left)
			)
		)
		(property "Value" ""
			(at 0 0 0)
			(layer "F.Fab")
			(effects
				(font
					(size 1.27 1.27)
				)
			)
		)
		(duplicate_pad_numbers_are_jumpers no)
		(fp_line
			(start 5.2578 2.499868)
			(end -5.2578 2.499868)
			(stroke
				(width 0.1524)
				(type default)
			)
			(layer "F.SilkS")
		)
		(fp_circle
			(center 0 2.499868)
			(end 5.2578 2.499868)
			(stroke
				(width 0.1524)
				(type default)
			)
			(fill no)
			(layer "F.SilkS")
		)
		(fp_poly
			(pts
				(arc
					(start 5.2578 2.499868)
					(mid 0 7.757922)
					(end -5.2578 2.499868)
				)
			)
			(stroke
				(width 0)
				(type default)
			)
			(fill yes)
			(layer "F.SilkS")
		)
		(fp_circle
			(center 0 2.499868)
			(end 5.2578 2.499868)
			(stroke
				(width 0.1)
				(type default)
			)
			(fill no)
			(layer "F.Fab")
		)
		(pad "1" thru_hole rect
			(at 0 0 270)
			(size 1.524 1.524)
			(drill 1.016)
			(layers "*.Cu" "*.Mask")
			(remove_unused_layers no)
			(net "P12V_BRICK")
			(clearance 0)
			(padstack
				(mode front_inner_back)
				(layer "Inner"
					(shape circle)
					(size 1.524 1.524)
					(clearance 0)
				)
				(layer "B.Cu"
					(shape rect)
					(size 1.524 1.524)
					(clearance 0)
				)
			)
		)
		(pad "2" thru_hole circle
			(at 0 4.99999 270)
			(size 1.524 1.524)
			(drill 1.016)
			(layers "*.Cu" "*.Mask")
			(remove_unused_layers no)
			(net "GND")
			(clearance 0)
		)
	)
)
